# T6G (Grand Teton) — schematic netlist excerpt (pin names and nets, part order shuffled) for the footprints in the layout excerpt that follows; sources: Cadence DE-HDL packaged netlist, KiCad conversion of 04192023_DAF0TMB3IC0_F0TG_MB_C_brd_V02_OCP.brd

J8  CONN4_HFK1040L0P1L7H  CONN4_HFK1040-L0P1L-7H IO  pkg HEADER1X4BHXA  page 151
  \1\  = UART_VCC_J8
  \2\  = UART_CPU0_SCM_LVC3_UART1_R_RX
  \3\  = UART_CPU0_SCM_LVC3_UART1_TX
  \4\  = GND

(kicad_pcb
	(version 20260206)
	(generator "pcbnew")
	(generator_version "10.0")
	(general
		(thickness 1.6)
		(legacy_teardrops no)
	)
	(paper "A4")
	(title_block
		(title "04192023_DAF0TMB3IC0_F0TG_MB_C_brd_V02_OCP.brd")
		(comment 1 "Grand Teton / footprints 1536-1536 of 8354")
	)
	(layers
		(0 "F.Cu" signal "TOP")
		(4 "In1.Cu" signal "GND")
		(6 "In2.Cu" signal "IN1")
		(8 "In3.Cu" signal "GND1")
		(10 "In4.Cu" signal "IN2")
		(12 "In5.Cu" signal "GND2")
		(14 "In6.Cu" signal "IN3")
		(16 "In7.Cu" signal "GND3")
		(18 "In8.Cu" signal "VCC")
		(20 "In9.Cu" signal "VCC1")
		(22 "In10.Cu" signal "GND4")
		(24 "In11.Cu" signal "IN4")
		(26 "In12.Cu" signal "GND5")
		(28 "In13.Cu" signal "IN5")
		(30 "In14.Cu" signal "GND6")
		(32 "In15.Cu" signal "IN6")
		(34 "In16.Cu" signal "GND7")
		(2 "B.Cu" signal "BOTTOM")
		(9 "F.Adhes" user "F.Adhesive")
		(11 "B.Adhes" user "B.Adhesive")
		(13 "F.Paste" user "Package Geometry/Pastemask Top")
		(15 "B.Paste" user "Package Geometry/Pastemask Bottom")
		(5 "F.SilkS" user "Ref Des/Silkscreen Top")
		(7 "B.SilkS" user "Ref Des/Silkscreen Bottom")
		(1 "F.Mask" user "Board Geometry/Soldermask Top")
		(3 "B.Mask" user "Board Geometry/Soldermask Bottom")
		(17 "Dwgs.User" user "User.Drawings")
		(19 "Cmts.User" user "User.Comments")
		(21 "Eco1.User" user "User.Eco1")
		(23 "Eco2.User" user "User.Eco2")
		(25 "Edge.Cuts" user "Board Geometry/Outline")
		(27 "Margin" user)
		(31 "F.CrtYd" user "Package Geometry/Place Bound Top")
		(29 "B.CrtYd" user "Package Geometry/Place Bound Bottom")
		(35 "F.Fab" user "Ref Des/Assembly Top")
		(33 "B.Fab" user "Ref Des/Assembly Bottom")
	)
	(footprint ""
		(layer "F.Cu")
		(at 317.284608 -15.337536 -90)
		(property "Reference" "J8"
			(at -4.073398 -0.944118 0)
			(unlocked yes)
			(layer "F.SilkS")
			(effects
				(font
					(size 0.7874 0.5842)
					(thickness 0.1524)
				)
				(justify left)
			)
		)
		(property "Value" ""
			(at 0 0 270)
			(layer "F.Fab")
			(effects
				(font
					(size 1.27 1.27)
				)
			)
		)
		(duplicate_pad_numbers_are_jumpers no)
		(fp_line
			(start -2.999994 7.999984)
			(end -0.899922 7.999984)
			(stroke
				(width 0.1524)
				(type default)
			)
			(layer "F.SilkS")
		)
		(fp_line
			(start -0.899922 7.999984)
			(end 1.700022 7.999984)
			(stroke
				(width 0.1524)
				(type default)
			)
			(layer "F.SilkS")
		)
		(fp_line
			(start 1.700022 7.999984)
			(end 1.700022 -1.999996)
			(stroke
				(width 0.1524)
				(type default)
			)
			(layer "F.SilkS")
		)
		(fp_line
			(start -2.500122 7.500112)
			(end -2.500122 6.568694)
			(stroke
				(width 0.1524)
				(type default)
			)
			(layer "F.SilkS")
		)
		(fp_line
			(start 1.199896 7.500112)
			(end -2.500122 7.500112)
			(stroke
				(width 0.1524)
				(type default)
			)
			(layer "F.SilkS")
		)
		(fp_line
			(start -2.500122 5.425694)
			(end -2.500122 -1.500124)
			(stroke
				(width 0.1524)
				(type default)
			)
			(layer "F.SilkS")
		)
		(fp_line
			(start 1.199896 4.99999)
			(end 1.199896 7.500112)
			(stroke
				(width 0.1524)
				(type default)
			)
			(layer "F.SilkS")
		)
		(fp_line
			(start 1.700022 4.99999)
			(end 1.199896 4.99999)
			(stroke
				(width 0.1524)
				(type default)
			)
			(layer "F.SilkS")
		)
		(fp_line
			(start 1.199896 0.999998)
			(end 1.700022 0.999998)
			(stroke
				(width 0.1524)
				(type default)
			)
			(layer "F.SilkS")
		)
		(fp_line
			(start -2.500122 -1.500124)
			(end 1.199896 -1.500124)
			(stroke
				(width 0.1524)
				(type default)
			)
			(layer "F.SilkS")
		)
		(fp_line
			(start 1.199896 -1.500124)
			(end 1.199896 0.999998)
			(stroke
				(width 0.1524)
				(type default)
			)
			(layer "F.SilkS")
		)
		(fp_line
			(start -2.999994 -1.999996)
			(end -2.999994 7.999984)
			(stroke
				(width 0.1524)
				(type default)
			)
			(layer "F.SilkS")
		)
		(fp_line
			(start 1.700022 -1.999996)
			(end -2.999994 -1.999996)
			(stroke
				(width 0.1524)
				(type default)
			)
			(layer "F.SilkS")
		)
		(fp_poly
			(pts
				(xy 0.762 -3.731006) (xy 0 -2.207006) (xy -0.762 -3.731006)
			)
			(stroke
				(width 0)
				(type default)
			)
			(fill yes)
			(layer "F.SilkS")
		)
		(fp_line
			(start -2.999994 7.999984)
			(end -0.899922 7.999984)
			(stroke
				(width 0.1)
				(type default)
			)
			(layer "F.Fab")
		)
		(fp_line
			(start -0.899922 7.999984)
			(end 1.700022 7.999984)
			(stroke
				(width 0.1)
				(type default)
			)
			(layer "F.Fab")
		)
		(fp_line
			(start 1.700022 7.999984)
			(end 1.700022 -1.999996)
			(stroke
				(width 0.1)
				(type default)
			)
			(layer "F.Fab")
		)
		(fp_line
			(start -2.500122 7.500112)
			(end -2.500122 6.606794)
			(stroke
				(width 0.1)
				(type default)
			)
			(layer "F.Fab")
		)
		(fp_line
			(start 1.199896 7.500112)
			(end -2.500122 7.500112)
			(stroke
				(width 0.1)
				(type default)
			)
			(layer "F.Fab")
		)
		(fp_line
			(start -2.500122 6.657594)
			(end -2.500122 -1.500124)
			(stroke
				(width 0.1)
				(type default)
			)
			(layer "F.Fab")
		)
		(fp_line
			(start 1.199896 4.99999)
			(end 1.199896 7.500112)
			(stroke
				(width 0.1)
				(type default)
			)
			(layer "F.Fab")
		)
		(fp_line
			(start 1.700022 4.99999)
			(end 1.199896 4.99999)
			(stroke
				(width 0.1)
				(type default)
			)
			(layer "F.Fab")
		)
		(fp_line
			(start 1.199896 0.999998)
			(end 1.700022 0.999998)
			(stroke
				(width 0.1)
				(type default)
			)
			(layer "F.Fab")
		)
		(fp_line
			(start -2.500122 -1.500124)
			(end 1.199896 -1.500124)
			(stroke
				(width 0.1)
				(type default)
			)
			(layer "F.Fab")
		)
		(fp_line
			(start 1.199896 -1.500124)
			(end 1.199896 0.999998)
			(stroke
				(width 0.1)
				(type default)
			)
			(layer "F.Fab")
		)
		(fp_line
			(start -2.999994 -1.999996)
			(end -2.999994 7.999984)
			(stroke
				(width 0.1)
				(type default)
			)
			(layer "F.Fab")
		)
		(fp_line
			(start 1.700022 -1.999996)
			(end -2.999994 -1.999996)
			(stroke
				(width 0.1)
				(type default)
			)
			(layer "F.Fab")
		)
		(fp_poly
			(pts
				(xy 0 -2.207006) (xy -0.762 -3.731006) (xy 0.762 -3.731006)
			)
			(stroke
				(width 0)
				(type default)
			)
			(fill yes)
			(layer "F.Fab")
		)
		(pad "" np_thru_hole circle
			(at -1.800098 5.999988)
			(size 1.143 1.143)
			(drill 1.143)
			(layers "*.Cu" "*.Mask")
			(clearance 0.381)
			(thermal_gap 0.381)
		)
		(pad "1" thru_hole rect
			(at 0 0)
			(size 1.2192 1.2192)
			(drill 0.8128)
			(layers "*.Cu" "*.Mask")
			(remove_unused_layers no)
			(net "UART_VCC_J8")
			(clearance 0.0508)
			(thermal_gap 0.0508)
			(padstack
				(mode front_inner_back)
				(layer "Inner"
					(shape circle)
					(size 1.2192 1.2192)
					(clearance 0.0508)
				)
				(layer "B.Cu"
					(shape rect)
					(size 1.2192 1.2192)
					(clearance 0.0508)
				)
			)
		)
		(pad "2" thru_hole circle
			(at 0 1.999996)
			(size 1.2192 1.2192)
			(drill 0.8128)
			(layers "*.Cu" "*.Mask")
			(remove_unused_layers no)
			(net "UART_CPU0_SCM_LVC3_UART1_R_RX")
			(clearance 0.0508)
			(thermal_gap 0.0508)
		)
		(pad "3" thru_hole circle
			(at 0 3.999992)
			(size 1.2192 1.2192)
			(drill 0.8128)
			(layers "*.Cu" "*.Mask")
			(remove_unused_layers no)
			(net "UART_CPU0_SCM_LVC3_UART1_TX")
			(clearance 0.0508)
			(thermal_gap 0.0508)
		)
		(pad "4" thru_hole circle
			(at 0 5.999988)
			(size 1.2192 1.2192)
			(drill 0.8128)
			(layers "*.Cu" "*.Mask")
			(remove_unused_layers no)
			(net "GND")
			(clearance 0.0508)
			(thermal_gap 0.0508)
		)
		(zone
			(layers "F.Cu" "B.Cu" "In1.Cu" "In2.Cu" "In3.Cu" "In4.Cu" "In5.Cu" "In6.Cu"
				"In7.Cu" "In8.Cu" "In9.Cu" "In10.Cu" "In11.Cu" "In12.Cu" "In13.Cu" "In14.Cu"
				"In15.Cu" "In16.Cu"
			)
			(hatch none 0.5)
			(connect_pads
				(clearance 0)
			)
			(min_thickness 0.25)
			(keepout
				(tracks not_allowed)
				(vias allowed)
				(pads allowed)
				(copperpour not_allowed)
				(footprints allowed)
			)
			(placement
				(enabled no)
				(sheetname "")
			)
			(fill
				(thermal_gap 0.5)
				(thermal_bridge_width 0.5)
				(island_removal_mode 0)
			)
			(polygon
				(pts
					(arc
						(start 310.266334 -17.126458)
						(mid 310.565401 -17.848471)
						(end 311.287414 -18.147538)
					)
					(arc
						(start 311.287414 -18.147538)
						(mid 312.295794 -17.139158)
						(end 311.287414 -16.130778)
					)
					(arc
						(start 311.262014 -16.130778)
						(mid 310.557962 -16.422406)
						(end 310.266334 -17.126458)
					)
				)
			)
		)
	)
)
